(kicad_pcb
	(version 20260206)
	(generator "pcbnew")
	(generator_version "10.0")
	(general
		(thickness 1.6)
		(legacy_teardrops no)
	)
	(paper "A4")
	(title_block
		(title "04192023_DAF0TMB3IC0_F0TG_MB_C_brd_V02_OCP.brd")
		(comment 1 "Grand Teton / footprint 4555 of 8354 (J99), pads 227-291 of 291")
	)
	(layers
		(0 "F.Cu" signal "TOP")
		(4 "In1.Cu" signal "GND")
		(6 "In2.Cu" signal "IN1")
		(8 "In3.Cu" signal "GND1")
		(10 "In4.Cu" signal "IN2")
		(12 "In5.Cu" signal "GND2")
		(14 "In6.Cu" signal "IN3")
		(16 "In7.Cu" signal "GND3")
		(18 "In8.Cu" signal "VCC")
		(20 "In9.Cu" signal "VCC1")
		(22 "In10.Cu" signal "GND4")
		(24 "In11.Cu" signal "IN4")
		(26 "In12.Cu" signal "GND5")
		(28 "In13.Cu" signal "IN5")
		(30 "In14.Cu" signal "GND6")
		(32 "In15.Cu" signal "IN6")
		(34 "In16.Cu" signal "GND7")
		(2 "B.Cu" signal "BOTTOM")
		(9 "F.Adhes" user "F.Adhesive")
		(11 "B.Adhes" user "B.Adhesive")
		(13 "F.Paste" user "Package Geometry/Pastemask Top")
		(15 "B.Paste" user "Package Geometry/Pastemask Bottom")
		(5 "F.SilkS" user "Ref Des/Silkscreen Top")
		(7 "B.SilkS" user "Ref Des/Silkscreen Bottom")
		(1 "F.Mask" user "Board Geometry/Soldermask Top")
		(3 "B.Mask" user "Board Geometry/Soldermask Bottom")
		(17 "Dwgs.User" user "User.Drawings")
		(19 "Cmts.User" user "User.Comments")
		(21 "Eco1.User" user "User.Eco1")
		(23 "Eco2.User" user "User.Eco2")
		(25 "Edge.Cuts" user "Board Geometry/Outline")
		(27 "Margin" user)
		(31 "F.CrtYd" user "Package Geometry/Place Bound Top")
		(29 "B.CrtYd" user "Package Geometry/Place Bound Bottom")
		(35 "F.Fab" user "Ref Des/Assembly Top")
		(33 "B.Fab" user "Ref Des/Assembly Bottom")
	)
	(footprint ""
		(layer "F.Cu")
		(at 196.654166 -255.560322 180)
		(property "Reference" "J99"
			(at -0.4318 -81.730088 0)
			(unlocked yes)
			(layer "F.SilkS")
			(effects
				(font
					(size 0.7874 0.5842)
					(thickness 0.1524)
				)
			)
		)
		(property "Value" ""
			(at 0 0 180)
			(layer "F.Fab")
			(effects
				(font
					(size 1.27 1.27)
				)
			)
		)
		(duplicate_pad_numbers_are_jumpers no)
		(pad "227" smd rect
			(at 2.050034 11.474958 90)
			(size 0.519938 1.4986)
			(layers "F.Cu" "F.Mask" "F.Paste")
			(net "M_K_CPU1_SB_PAR")
		)
		(pad "228" smd rect
			(at 2.050034 12.325096 90)
			(size 0.519938 1.4986)
			(layers "F.Cu" "F.Mask" "F.Paste")
			(net "GND")
		)
		(pad "229" smd rect
			(at 2.050034 13.17498 90)
			(size 0.519938 1.4986)
			(layers "F.Cu" "F.Mask" "F.Paste")
			(net "M_K_CPU1_SB_CS_N<1>")
		)
		(pad "230" smd rect
			(at 2.050034 14.025118 90)
			(size 0.519938 1.4986)
			(layers "F.Cu" "F.Mask" "F.Paste")
			(net "GND")
		)
		(pad "231" smd rect
			(at 2.050034 14.875002 90)
			(size 0.519938 1.4986)
			(layers "F.Cu" "F.Mask" "F.Paste")
			(net "Net_2401")
		)
		(pad "232" smd rect
			(at 2.050034 15.724886 90)
			(size 0.519938 1.4986)
			(layers "F.Cu" "F.Mask" "F.Paste")
			(net "Net_2402")
		)
		(pad "233" smd rect
			(at 2.050034 16.575024 90)
			(size 0.519938 1.4986)
			(layers "F.Cu" "F.Mask" "F.Paste")
			(net "GND")
		)
		(pad "234" smd rect
			(at 2.050034 17.424908 90)
			(size 0.519938 1.4986)
			(layers "F.Cu" "F.Mask" "F.Paste")
			(net "M_K_CPU1_SB_CB<6>")
		)
		(pad "235" smd rect
			(at 2.050034 18.275046 90)
			(size 0.519938 1.4986)
			(layers "F.Cu" "F.Mask" "F.Paste")
			(net "GND")
		)
		(pad "236" smd rect
			(at 2.050034 19.12493 90)
			(size 0.519938 1.4986)
			(layers "F.Cu" "F.Mask" "F.Paste")
			(net "M_K_CPU1_SB_CB<7>")
		)
		(pad "237" smd rect
			(at 2.050034 19.975068 90)
			(size 0.519938 1.4986)
			(layers "F.Cu" "F.Mask" "F.Paste")
			(net "GND")
		)
		(pad "238" smd rect
			(at 2.050034 20.824952 90)
			(size 0.519938 1.4986)
			(layers "F.Cu" "F.Mask" "F.Paste")
			(net "M_K_CPU1_SB_DQS_DN<4>")
		)
		(pad "239" smd rect
			(at 2.050034 21.67509 90)
			(size 0.519938 1.4986)
			(layers "F.Cu" "F.Mask" "F.Paste")
			(net "M_K_CPU1_SB_DQS_DP<4>")
		)
		(pad "240" smd rect
			(at 2.050034 22.524974 90)
			(size 0.519938 1.4986)
			(layers "F.Cu" "F.Mask" "F.Paste")
			(net "GND")
		)
		(pad "241" smd rect
			(at 2.050034 23.375112 90)
			(size 0.519938 1.4986)
			(layers "F.Cu" "F.Mask" "F.Paste")
			(net "M_K_CPU1_SB_CB<2>")
		)
		(pad "242" smd rect
			(at 2.050034 24.224996 90)
			(size 0.519938 1.4986)
			(layers "F.Cu" "F.Mask" "F.Paste")
			(net "GND")
		)
		(pad "243" smd rect
			(at 2.050034 25.07488 90)
			(size 0.519938 1.4986)
			(layers "F.Cu" "F.Mask" "F.Paste")
			(net "M_K_CPU1_SB_CB<3>")
		)
		(pad "244" smd rect
			(at 2.050034 25.925018 90)
			(size 0.519938 1.4986)
			(layers "F.Cu" "F.Mask" "F.Paste")
			(net "GND")
		)
		(pad "245" smd rect
			(at 2.050034 26.774902 90)
			(size 0.519938 1.4986)
			(layers "F.Cu" "F.Mask" "F.Paste")
			(net "M_K_CPU1_SB_DQ<2>")
		)
		(pad "246" smd rect
			(at 2.050034 27.62504 90)
			(size 0.519938 1.4986)
			(layers "F.Cu" "F.Mask" "F.Paste")
			(net "GND")
		)
		(pad "247" smd rect
			(at 2.050034 28.474924 90)
			(size 0.519938 1.4986)
			(layers "F.Cu" "F.Mask" "F.Paste")
			(net "M_K_CPU1_SB_DQ<3>")
		)
		(pad "248" smd rect
			(at 2.050034 29.325062 90)
			(size 0.519938 1.4986)
			(layers "F.Cu" "F.Mask" "F.Paste")
			(net "GND")
		)
		(pad "249" smd rect
			(at 2.050034 30.174946 90)
			(size 0.519938 1.4986)
			(layers "F.Cu" "F.Mask" "F.Paste")
			(net "M_K_CPU1_SB_DQS_DN<5>")
		)
		(pad "250" smd rect
			(at 2.050034 31.025084 90)
			(size 0.519938 1.4986)
			(layers "F.Cu" "F.Mask" "F.Paste")
			(net "M_K_CPU1_SB_DQS_DP<5>")
		)
		(pad "251" smd rect
			(at 2.050034 31.874968 90)
			(size 0.519938 1.4986)
			(layers "F.Cu" "F.Mask" "F.Paste")
			(net "GND")
		)
		(pad "252" smd rect
			(at 2.050034 32.725106 90)
			(size 0.519938 1.4986)
			(layers "F.Cu" "F.Mask" "F.Paste")
			(net "M_K_CPU1_SB_DQ<6>")
		)
		(pad "253" smd rect
			(at 2.050034 33.57499 90)
			(size 0.519938 1.4986)
			(layers "F.Cu" "F.Mask" "F.Paste")
			(net "GND")
		)
		(pad "254" smd rect
			(at 2.050034 34.425128 90)
			(size 0.519938 1.4986)
			(layers "F.Cu" "F.Mask" "F.Paste")
			(net "M_K_CPU1_SB_DQ<7>")
		)
		(pad "255" smd rect
			(at 2.050034 35.275012 90)
			(size 0.519938 1.4986)
			(layers "F.Cu" "F.Mask" "F.Paste")
			(net "GND")
		)
		(pad "256" smd rect
			(at 2.050034 36.124896 90)
			(size 0.519938 1.4986)
			(layers "F.Cu" "F.Mask" "F.Paste")
			(net "M_K_CPU1_SB_DQ<10>")
		)
		(pad "257" smd rect
			(at 2.050034 36.975034 90)
			(size 0.519938 1.4986)
			(layers "F.Cu" "F.Mask" "F.Paste")
			(net "GND")
		)
		(pad "258" smd rect
			(at 2.050034 37.824918 90)
			(size 0.519938 1.4986)
			(layers "F.Cu" "F.Mask" "F.Paste")
			(net "M_K_CPU1_SB_DQ<11>")
		)
		(pad "259" smd rect
			(at 2.050034 38.675056 90)
			(size 0.519938 1.4986)
			(layers "F.Cu" "F.Mask" "F.Paste")
			(net "GND")
		)
		(pad "260" smd rect
			(at 2.050034 39.52494 90)
			(size 0.519938 1.4986)
			(layers "F.Cu" "F.Mask" "F.Paste")
			(net "M_K_CPU1_SB_DQS_DN<6>")
		)
		(pad "261" smd rect
			(at 2.050034 40.375078 90)
			(size 0.519938 1.4986)
			(layers "F.Cu" "F.Mask" "F.Paste")
			(net "M_K_CPU1_SB_DQS_DP<6>")
		)
		(pad "262" smd rect
			(at 2.050034 41.224962 90)
			(size 0.519938 1.4986)
			(layers "F.Cu" "F.Mask" "F.Paste")
			(net "GND")
		)
		(pad "263" smd rect
			(at 2.050034 42.0751 90)
			(size 0.519938 1.4986)
			(layers "F.Cu" "F.Mask" "F.Paste")
			(net "M_K_CPU1_SB_DQ<14>")
		)
		(pad "264" smd rect
			(at 2.050034 42.924984 90)
			(size 0.519938 1.4986)
			(layers "F.Cu" "F.Mask" "F.Paste")
			(net "GND")
		)
		(pad "265" smd rect
			(at 2.050034 43.775122 90)
			(size 0.519938 1.4986)
			(layers "F.Cu" "F.Mask" "F.Paste")
			(net "M_K_CPU1_SB_DQ<15>")
		)
		(pad "266" smd rect
			(at 2.050034 44.625006 90)
			(size 0.519938 1.4986)
			(layers "F.Cu" "F.Mask" "F.Paste")
			(net "GND")
		)
		(pad "267" smd rect
			(at 2.050034 45.47489 90)
			(size 0.519938 1.4986)
			(layers "F.Cu" "F.Mask" "F.Paste")
			(net "M_K_CPU1_SB_DQ<18>")
		)
		(pad "268" smd rect
			(at 2.050034 46.325028 90)
			(size 0.519938 1.4986)
			(layers "F.Cu" "F.Mask" "F.Paste")
			(net "GND")
		)
		(pad "269" smd rect
			(at 2.050034 47.174912 90)
			(size 0.519938 1.4986)
			(layers "F.Cu" "F.Mask" "F.Paste")
			(net "M_K_CPU1_SB_DQ<19>")
		)
		(pad "270" smd rect
			(at 2.050034 48.02505 90)
			(size 0.519938 1.4986)
			(layers "F.Cu" "F.Mask" "F.Paste")
			(net "GND")
		)
		(pad "271" smd rect
			(at 2.050034 48.874934 90)
			(size 0.519938 1.4986)
			(layers "F.Cu" "F.Mask" "F.Paste")
			(net "M_K_CPU1_SB_DQS_DN<7>")
		)
		(pad "272" smd rect
			(at 2.050034 49.725072 90)
			(size 0.519938 1.4986)
			(layers "F.Cu" "F.Mask" "F.Paste")
			(net "M_K_CPU1_SB_DQS_DP<7>")
		)
		(pad "273" smd rect
			(at 2.050034 50.574956 90)
			(size 0.519938 1.4986)
			(layers "F.Cu" "F.Mask" "F.Paste")
			(net "GND")
		)
		(pad "274" smd rect
			(at 2.050034 51.425094 90)
			(size 0.519938 1.4986)
			(layers "F.Cu" "F.Mask" "F.Paste")
			(net "M_K_CPU1_SB_DQ<22>")
		)
		(pad "275" smd rect
			(at 2.050034 52.274978 90)
			(size 0.519938 1.4986)
			(layers "F.Cu" "F.Mask" "F.Paste")
			(net "GND")
		)
		(pad "276" smd rect
			(at 2.050034 53.125116 90)
			(size 0.519938 1.4986)
			(layers "F.Cu" "F.Mask" "F.Paste")
			(net "M_K_CPU1_SB_DQ<23>")
		)
		(pad "277" smd rect
			(at 2.050034 53.975 90)
			(size 0.519938 1.4986)
			(layers "F.Cu" "F.Mask" "F.Paste")
			(net "GND")
		)
		(pad "278" smd rect
			(at 2.050034 54.824884 90)
			(size 0.519938 1.4986)
			(layers "F.Cu" "F.Mask" "F.Paste")
			(net "M_K_CPU1_SB_DQ<26>")
		)
		(pad "279" smd rect
			(at 2.050034 55.675022 90)
			(size 0.519938 1.4986)
			(layers "F.Cu" "F.Mask" "F.Paste")
			(net "GND")
		)
		(pad "280" smd rect
			(at 2.050034 56.524906 90)
			(size 0.519938 1.4986)
			(layers "F.Cu" "F.Mask" "F.Paste")
			(net "M_K_CPU1_SB_DQ<27>")
		)
		(pad "281" smd rect
			(at 2.050034 57.375044 90)
			(size 0.519938 1.4986)
			(layers "F.Cu" "F.Mask" "F.Paste")
			(net "GND")
		)
		(pad "282" smd rect
			(at 2.050034 58.224928 90)
			(size 0.519938 1.4986)
			(layers "F.Cu" "F.Mask" "F.Paste")
			(net "M_K_CPU1_SB_DQS_DN<8>")
		)
		(pad "283" smd rect
			(at 2.050034 59.075066 90)
			(size 0.519938 1.4986)
			(layers "F.Cu" "F.Mask" "F.Paste")
			(net "M_K_CPU1_SB_DQS_DP<8>")
		)
		(pad "284" smd rect
			(at 2.050034 59.92495 90)
			(size 0.519938 1.4986)
			(layers "F.Cu" "F.Mask" "F.Paste")
			(net "GND")
		)
		(pad "285" smd rect
			(at 2.050034 60.775088 90)
			(size 0.519938 1.4986)
			(layers "F.Cu" "F.Mask" "F.Paste")
			(net "M_K_CPU1_SB_DQ<30>")
		)
		(pad "286" smd rect
			(at 2.050034 61.624972 90)
			(size 0.519938 1.4986)
			(layers "F.Cu" "F.Mask" "F.Paste")
			(net "GND")
		)
		(pad "287" smd rect
			(at 2.050034 62.47511 90)
			(size 0.519938 1.4986)
			(layers "F.Cu" "F.Mask" "F.Paste")
			(net "M_K_CPU1_SB_DQ<31>")
		)
		(pad "288" smd rect
			(at 2.050034 63.324994 90)
			(size 0.519938 1.4986)
			(layers "F.Cu" "F.Mask" "F.Paste")
			(net "GND")
		)
		(pad "G1" thru_hole oval
			(at 0 -68.97497 90)
			(size 1.7272 3.4798)
			(drill oval 1.2192 2.4638)
			(layers "*.Cu" "*.Mask")
			(remove_unused_layers no)
			(net "GND")
			(clearance 0.127)
			(thermal_gap 0.127)
		)
		(pad "G2" thru_hole oval
			(at 0 3.875024 90)
			(size 1.7272 3.4798)
			(drill oval 1.2192 2.4638)
			(layers "*.Cu" "*.Mask")
			(remove_unused_layers no)
			(net "GND")
			(clearance 0.127)
			(thermal_gap 0.127)
		)
		(pad "G3" thru_hole oval
			(at 0 68.97497 90)
			(size 1.7272 3.4798)
			(drill oval 1.2192 2.4638)
			(layers "*.Cu" "*.Mask")
			(remove_unused_layers no)
			(net "GND")
			(clearance 0.127)
			(thermal_gap 0.127)
		)
	)
)
